(kicad_pcb
	(version 20260206)
	(generator "pcbnew")
	(generator_version "10.0")
	(general
		(thickness 1.21888)
		(legacy_teardrops no)
	)
	(paper "A4")
	(title_block
		(title "timecard-v8 — TimeCard-DC-V8_EXP.PcbDoc")
		(comment 1 "Time Appliance Project (Time Card) / footprints 40-51 of 288")
	)
	(layers
		(0 "F.Cu" signal "TOP")
		(4 "In1.Cu" signal "SGND")
		(6 "In2.Cu" signal "IN1")
		(8 "In3.Cu" signal "IN2")
		(10 "In4.Cu" signal "SGND1")
		(2 "B.Cu" signal "BOTTOM")
		(9 "F.Adhes" user "F.Adhesive")
		(11 "B.Adhes" user "B.Adhesive")
		(13 "F.Paste" user "Top Paste")
		(15 "B.Paste" user "Bottom Paste")
		(5 "F.SilkS" user "Top Overlay")
		(7 "B.SilkS" user "Bottom Overlay")
		(1 "F.Mask" user "Top Solder")
		(3 "B.Mask" user "Bottom Solder")
		(17 "Dwgs.User" user "User.Drawings")
		(19 "Cmts.User" user "User.Comments")
		(21 "Eco1.User" user "User.Eco1")
		(23 "Eco2.User" user "User.Eco2")
		(25 "Edge.Cuts" user)
		(27 "Margin" user)
		(31 "F.CrtYd" user "Top Courtyard")
		(29 "B.CrtYd" user "Bottom Courtyard")
		(35 "F.Fab" user "Top Component Center")
		(33 "B.Fab" user "Bottom Component Center")
	)
	(footprint "Vault:FP-IHLP-2525EZ-FP_2_413x3-MFG"
		(layer "F.Cu")
		(at 219.7261 109.9162)
		(property "Reference" "L1"
			(at 3.906655 2.1 270)
			(unlocked yes)
			(layer "F.SilkS")
			(effects
				(font
					(size 0.762 0.762)
					(thickness 0.2286)
				)
				(justify left bottom)
			)
		)
		(property "Value" "2.2uH_10A"
			(at -22.3845 0.209845 0)
			(unlocked yes)
			(layer "F.SilkS")
			(hide yes)
			(effects
				(font
					(size 0.762 0.762)
					(thickness 0.2286)
				)
				(justify left bottom)
			)
		)
		(sheetname "POWER")
		(sheetfile "POWER.kicad_sch")
		(duplicate_pad_numbers_are_jumpers no)
		(fp_line
			(start -3.362 -3.362)
			(end 3.362 -3.362)
			(stroke
				(width 0.2)
				(type solid)
			)
			(layer "F.SilkS")
		)
		(fp_line
			(start -3.362 -2.0895)
			(end -3.362 -3.362)
			(stroke
				(width 0.2)
				(type solid)
			)
			(layer "F.SilkS")
		)
		(fp_line
			(start -3.362 3.362)
			(end -3.362 2.0895)
			(stroke
				(width 0.2)
				(type solid)
			)
			(layer "F.SilkS")
		)
		(fp_line
			(start -3.362 3.362)
			(end 3.362 3.362)
			(stroke
				(width 0.2)
				(type solid)
			)
			(layer "F.SilkS")
		)
		(fp_line
			(start 3.362 -2.0895)
			(end 3.362 -3.362)
			(stroke
				(width 0.2)
				(type solid)
			)
			(layer "F.SilkS")
		)
		(fp_line
			(start 3.362 3.362)
			(end 3.362 2.0895)
			(stroke
				(width 0.2)
				(type solid)
			)
			(layer "F.SilkS")
		)
		(fp_line
			(start -4.2275 -3.462)
			(end 4.2275 -3.462)
			(stroke
				(width 0.2)
				(type solid)
			)
			(layer "F.CrtYd")
		)
		(fp_line
			(start -4.2275 3.462)
			(end -4.2275 -3.462)
			(stroke
				(width 0.2)
				(type solid)
			)
			(layer "F.CrtYd")
		)
		(fp_line
			(start -4.2275 3.462)
			(end 4.2275 3.462)
			(stroke
				(width 0.2)
				(type solid)
			)
			(layer "F.CrtYd")
		)
		(fp_line
			(start 4.2275 3.462)
			(end 4.2275 -3.462)
			(stroke
				(width 0.2)
				(type solid)
			)
			(layer "F.CrtYd")
		)
		(fp_line
			(start -4.2275 -3.462)
			(end 4.2275 -3.462)
			(stroke
				(width 0.2)
				(type solid)
			)
			(layer "F.Fab")
		)
		(fp_line
			(start -4.2275 3.462)
			(end -4.2275 -3.462)
			(stroke
				(width 0.2)
				(type solid)
			)
			(layer "F.Fab")
		)
		(fp_line
			(start -4.2275 3.462)
			(end 4.2275 3.462)
			(stroke
				(width 0.2)
				(type solid)
			)
			(layer "F.Fab")
		)
		(fp_line
			(start -0.5 0)
			(end 0.5 0)
			(stroke
				(width 0.1)
				(type solid)
			)
			(layer "F.Fab")
		)
		(fp_line
			(start 0 0.5)
			(end 0 -0.5)
			(stroke
				(width 0.1)
				(type solid)
			)
			(layer "F.Fab")
		)
		(fp_line
			(start 4.2275 3.462)
			(end 4.2275 -3.462)
			(stroke
				(width 0.2)
				(type solid)
			)
			(layer "F.Fab")
		)
		(fp_text user "${REFERENCE}"
			(at -0.00001 0.10711 360)
			(unlocked yes)
			(layer "F.Fab")
			(effects
				(font
					(face "Arial")
					(size 0.63 0.63)
					(thickness 0.1)
				)
				(justify left bottom)
			)
		)
		(pad "1" smd rect
			(at -2.921 0)
			(size 2.413 3.429)
			(layers "F.Cu" "F.Mask" "F.Paste")
			(net "NetL1_1")
			(solder_mask_margin 0)
			(solder_paste_margin 0)
		)
		(pad "2" smd rect
			(at 2.921 0)
			(size 2.413 3.429)
			(layers "F.Cu" "F.Mask" "F.Paste")
			(net "P5V_SENSE")
			(solder_mask_margin 0)
			(solder_paste_margin 0)
		)
	)
	(footprint "Vault:CAPC1608X87X45ML20T05"
		(layer "F.Cu")
		(at 207.4261 85.7162 -90)
		(property "Reference" "C2"
			(at -1.6 -0.993345 90)
			(unlocked yes)
			(layer "F.SilkS")
			(effects
				(font
					(size 0.762 0.762)
					(thickness 0.2286)
				)
				(justify left bottom)
			)
		)
		(property "Value" "0.1uF"
			(at 2.225445 1.4493 0)
			(unlocked yes)
			(layer "F.SilkS")
			(hide yes)
			(effects
				(font
					(size 0.762 0.762)
					(thickness 0.2286)
				)
				(justify left bottom)
			)
		)
		(sheetname "POWER")
		(sheetfile "POWER.kicad_sch")
		(duplicate_pad_numbers_are_jumpers no)
		(pad "1" smd rect
			(at -0.7 0)
			(size 1.1 1.05)
			(layers "F.Cu" "F.Mask" "F.Paste")
			(net "GND")
		)
		(pad "2" smd rect
			(at 0.7 0)
			(size 1.1 1.05)
			(layers "F.Cu" "F.Mask" "F.Paste")
			(net "+12V")
		)
	)
	(footprint "Vault:CAPC1608X87X45ML20T05"
		(layer "F.Cu")
		(at 233.0261 59.2162 180)
		(property "Reference" "C37"
			(at -0.7286 1.273079 0)
			(unlocked yes)
			(layer "F.SilkS")
			(effects
				(font
					(size 0.762 0.762)
					(thickness 0.2286)
				)
			)
		)
		(property "Value" "0.1uF"
			(at 2.069035 2.630671 180)
			(unlocked yes)
			(layer "F.SilkS")
			(hide yes)
			(effects
				(font
					(size 0.762 0.762)
					(thickness 0.2286)
				)
			)
		)
		(sheetname "GPS_IMU_SENSORS")
		(sheetfile "GPS_IMU_SENSORS.kicad_sch")
		(duplicate_pad_numbers_are_jumpers no)
		(pad "1" smd rect
			(at -0.7 0 270)
			(size 1.1 1.05)
			(layers "F.Cu" "F.Mask" "F.Paste")
			(net "GND")
		)
		(pad "2" smd rect
			(at 0.7 0 270)
			(size 1.1 1.05)
			(layers "F.Cu" "F.Mask" "F.Paste")
			(net "+5.0V")
		)
	)
	(footprint "Vault:CAPC1608X87X45ML20T05"
		(layer "F.Cu")
		(at 77.3261 65.2162 -90)
		(property "Reference" "C54"
			(at -2.8714 -0.073069 270)
			(unlocked yes)
			(layer "F.SilkS")
			(effects
				(font
					(size 0.762 0.762)
					(thickness 0.2286)
				)
			)
		)
		(property "Value" "0.1uF"
			(at 2.069035 2.630671 270)
			(unlocked yes)
			(layer "F.SilkS")
			(hide yes)
			(effects
				(font
					(size 0.762 0.762)
					(thickness 0.2286)
				)
			)
		)
		(sheetname "GPS_IMU_SENSORS")
		(sheetfile "GPS_IMU_SENSORS.kicad_sch")
		(duplicate_pad_numbers_are_jumpers no)
		(pad "1" smd rect
			(at -0.7 0)
			(size 1.1 1.05)
			(layers "F.Cu" "F.Mask" "F.Paste")
			(net "GND")
		)
		(pad "2" smd rect
			(at 0.7 0)
			(size 1.1 1.05)
			(layers "F.Cu" "F.Mask" "F.Paste")
			(net "+5.0V")
		)
	)
	(footprint "Vault:RESC1005X40X25ML05T10"
		(layer "F.Cu")
		(at 203.3261 106.0162)
		(property "Reference" "R63"
			(at -0.1714 -1.173079 0)
			(unlocked yes)
			(layer "F.SilkS")
			(effects
				(font
					(size 0.762 0.762)
					(thickness 0.2286)
				)
			)
		)
		(property "Value" "470_1%_0402"
			(at -2.884671 8.036475 270)
			(unlocked yes)
			(layer "F.SilkS")
			(hide yes)
			(effects
				(font
					(size 0.762 0.762)
					(thickness 0.2286)
				)
			)
		)
		(sheetname "POWER")
		(sheetfile "POWER.kicad_sch")
		(duplicate_pad_numbers_are_jumpers no)
		(pad "1" smd rect
			(at -0.475 0 90)
			(size 0.65 0.7)
			(layers "F.Cu" "F.Mask" "F.Paste")
			(net "GND")
		)
		(pad "2" smd rect
			(at 0.475 0 90)
			(size 0.65 0.7)
			(layers "F.Cu" "F.Mask" "F.Paste")
			(net "P5V_FB")
		)
	)
	(footprint "Vault:M08A_N"
		(layer "F.Cu")
		(at 136.5261 85.9636)
		(property "Reference" "U3"
			(at 2.528605 -3.020469 0)
			(unlocked yes)
			(layer "F.SilkS")
			(effects
				(font
					(size 0.762 0.762)
					(thickness 0.2286)
				)
			)
		)
		(property "Value" "DS90LV027AQMA"
			(at 6.35958 4.332471 0)
			(unlocked yes)
			(layer "F.SilkS")
			(hide yes)
			(effects
				(font
					(size 0.762 0.762)
					(thickness 0.2286)
				)
			)
		)
		(sheetname "MAC")
		(sheetfile "MAC.kicad_sch")
		(duplicate_pad_numbers_are_jumpers no)
		(fp_line
			(start -0.9 -2.5)
			(end 0.9 -2.5)
			(stroke
				(width 0.2)
				(type solid)
			)
			(layer "F.SilkS")
		)
		(fp_line
			(start -0.9 2.5)
			(end -0.9 -2.5)
			(stroke
				(width 0.2)
				(type solid)
			)
			(layer "F.SilkS")
		)
		(fp_line
			(start -0.9 2.5)
			(end 0.9 2.5)
			(stroke
				(width 0.2)
				(type solid)
			)
			(layer "F.SilkS")
		)
		(fp_line
			(start 0.9 2.5)
			(end 0.9 -2.5)
			(stroke
				(width 0.2)
				(type solid)
			)
			(layer "F.SilkS")
		)
		(fp_circle
			(center -2.4 -2.755)
			(end -2.4 -2.88)
			(stroke
				(width 0.25)
				(type solid)
			)
			(fill no)
			(layer "F.SilkS")
		)
		(fp_circle
			(center -0.1 -1.7)
			(end -0.1 -1.9)
			(stroke
				(width 0.4)
				(type solid)
			)
			(fill no)
			(layer "F.SilkS")
		)
		(pad "1" smd oval
			(at -2.4 -1.905 90)
			(size 0.6 2.2)
			(layers "F.Cu" "F.Mask" "F.Paste")
			(net "+3.3V")
		)
		(pad "2" smd oval
			(at -2.4 -0.635 90)
			(size 0.6 2.2)
			(layers "F.Cu" "F.Mask" "F.Paste")
			(net "FPGA_MAC_PPS_IN1-")
		)
		(pad "3" smd oval
			(at -2.4 0.635 90)
			(size 0.6 2.2)
			(layers "F.Cu" "F.Mask" "F.Paste")
			(net "FPGA_MAC_PPS_DIFF_IN0")
		)
		(pad "4" smd oval
			(at -2.4 1.905 90)
			(size 0.6 2.2)
			(layers "F.Cu" "F.Mask" "F.Paste")
			(net "GND")
		)
		(pad "5" smd oval
			(at 2.4 1.905 90)
			(size 0.6 2.2)
			(layers "F.Cu" "F.Mask" "F.Paste")
			(net "MAC_PPS_IN0-")
		)
		(pad "6" smd oval
			(at 2.4 0.635 90)
			(size 0.6 2.2)
			(layers "F.Cu" "F.Mask" "F.Paste")
			(net "MAC_PPS_IN0+")
		)
		(pad "7" smd oval
			(at 2.4 -0.635 90)
			(size 0.6 2.2)
			(layers "F.Cu" "F.Mask" "F.Paste")
			(net "MAC_PPS_IN1+")
		)
		(pad "8" smd oval
			(at 2.4 -1.905 90)
			(size 0.6 2.2)
			(layers "F.Cu" "F.Mask" "F.Paste")
			(net "MAC_PPS_IN1-")
		)
	)
	(footprint "Vault:TECO-1909763-1_V"
		(layer "F.Cu")
		(at 74.3761 108.6162 -90)
		(property "Reference" "J2"
			(at -2.973079 1.271395 0)
			(unlocked yes)
			(layer "F.SilkS")
			(effects
				(font
					(size 0.762 0.762)
					(thickness 0.2286)
				)
			)
		)
		(property "Value" "1909763-1"
			(at 4.582685 3.722871 270)
			(unlocked yes)
			(layer "F.SilkS")
			(hide yes)
			(effects
				(font
					(size 0.762 0.762)
					(thickness 0.2286)
				)
			)
		)
		(sheetname "USER_IO")
		(sheetfile "USER_IO.kicad_sch")
		(duplicate_pad_numbers_are_jumpers no)
		(fp_line
			(start 0.55 -1.3)
			(end -0.55 -1.3)
			(stroke
				(width 0.2)
				(type solid)
			)
			(layer "F.SilkS")
		)
		(fp_circle
			(center -1.778 1.65)
			(end -1.903 1.65)
			(stroke
				(width 0.25)
				(type solid)
			)
			(fill no)
			(layer "F.SilkS")
		)
		(pad "1" smd rect
			(at -1.475 0 270)
			(size 1.05 2.2)
			(layers "F.Cu" "F.Mask" "F.Paste")
			(net "GND")
		)
		(pad "2" smd rect
			(at 0 1.525 270)
			(size 1 1.05)
			(layers "F.Cu" "F.Mask" "F.Paste")
			(net "NetAN2_1")
		)
		(pad "3" smd rect
			(at 1.475 0 270)
			(size 1.05 2.2)
			(layers "F.Cu" "F.Mask" "F.Paste")
			(net "GND")
		)
	)
	(footprint "Vault:CAPC1608X87X45ML20T05"
		(layer "F.Cu")
		(at 91.4261 65.4162 -90)
		(property "Reference" "C43"
			(at -2.9714 0.226931 270)
			(unlocked yes)
			(layer "F.SilkS")
			(effects
				(font
					(size 0.762 0.762)
					(thickness 0.2286)
				)
			)
		)
		(property "Value" "0.1uF"
			(at 2.069035 2.630671 270)
			(unlocked yes)
			(layer "F.SilkS")
			(hide yes)
			(effects
				(font
					(size 0.762 0.762)
					(thickness 0.2286)
				)
			)
		)
		(sheetname "GPS_IMU_SENSORS")
		(sheetfile "GPS_IMU_SENSORS.kicad_sch")
		(duplicate_pad_numbers_are_jumpers no)
		(pad "1" smd rect
			(at -0.7 0)
			(size 1.1 1.05)
			(layers "F.Cu" "F.Mask" "F.Paste")
			(net "GND")
		)
		(pad "2" smd rect
			(at 0.7 0)
			(size 1.1 1.05)
			(layers "F.Cu" "F.Mask" "F.Paste")
			(net "+3.3V")
		)
	)
	(footprint "Vault:RESC1608X55X30NL15T15"
		(layer "F.Cu")
		(at 75.1261 55.6162 90)
		(property "Reference" "R39"
			(at -5.7714 0.026921 90)
			(unlocked yes)
			(layer "F.SilkS")
			(effects
				(font
					(size 0.762 0.762)
					(thickness 0.2286)
				)
			)
		)
		(property "Value" "200 OHM"
			(at -2.935471 4.78626 0)
			(unlocked yes)
			(layer "F.SilkS")
			(hide yes)
			(effects
				(font
					(size 0.762 0.762)
					(thickness 0.2286)
				)
			)
		)
		(sheetname "USER_IO_STATUS")
		(sheetfile "USER_IO_STATUS.kicad_sch")
		(duplicate_pad_numbers_are_jumpers no)
		(pad "1" smd rect
			(at -0.675 0 180)
			(size 0.95 0.8)
			(layers "F.Cu" "F.Mask" "F.Paste")
			(net "LED4")
		)
		(pad "2" smd rect
			(at 0.675 0 180)
			(size 0.95 0.8)
			(layers "F.Cu" "F.Mask" "F.Paste")
			(net "NetD11_1")
		)
	)
	(footprint "Vault:FP-CC0603-DA-MFG"
		(layer "F.Cu")
		(at 208.5261 129.2162 180)
		(property "Reference" "C74"
			(at 0.2286 -1.473079 180)
			(unlocked yes)
			(layer "F.SilkS")
			(effects
				(font
					(size 0.762 0.762)
					(thickness 0.2286)
				)
			)
		)
		(property "Value" "0.1uF_50V_0603"
			(at -3.075151 9.686815 90)
			(unlocked yes)
			(layer "F.SilkS")
			(hide yes)
			(effects
				(font
					(size 0.762 0.762)
					(thickness 0.2286)
				)
			)
		)
		(sheetname "POWER")
		(sheetfile "POWER.kicad_sch")
		(duplicate_pad_numbers_are_jumpers no)
		(fp_line
			(start 0.85 0.85)
			(end -0.85 0.85)
			(stroke
				(width 0.2)
				(type solid)
			)
			(layer "F.SilkS")
		)
		(fp_line
			(start 0.85 -0.85)
			(end -0.85 -0.85)
			(stroke
				(width 0.2)
				(type solid)
			)
			(layer "F.SilkS")
		)
		(fp_line
			(start 1.35 0.75)
			(end -1.35 0.75)
			(stroke
				(width 0.2)
				(type solid)
			)
			(layer "F.CrtYd")
		)
		(fp_line
			(start 1.35 -0.75)
			(end 1.35 0.75)
			(stroke
				(width 0.2)
				(type solid)
			)
			(layer "F.CrtYd")
		)
		(fp_line
			(start 1.35 -0.75)
			(end -1.35 -0.75)
			(stroke
				(width 0.2)
				(type solid)
			)
			(layer "F.CrtYd")
		)
		(fp_line
			(start -1.35 -0.75)
			(end -1.35 0.75)
			(stroke
				(width 0.2)
				(type solid)
			)
			(layer "F.CrtYd")
		)
		(fp_line
			(start 1.35 0.75)
			(end -1.35 0.75)
			(stroke
				(width 0.2)
				(type solid)
			)
			(layer "F.Fab")
		)
		(fp_line
			(start 1.35 -0.75)
			(end 1.35 0.75)
			(stroke
				(width 0.2)
				(type solid)
			)
			(layer "F.Fab")
		)
		(fp_line
			(start 1.35 -0.75)
			(end -1.35 -0.75)
			(stroke
				(width 0.2)
				(type solid)
			)
			(layer "F.Fab")
		)
		(fp_line
			(start 0.5 0)
			(end -0.5 0)
			(stroke
				(width 0.1)
				(type solid)
			)
			(layer "F.Fab")
		)
		(fp_line
			(start 0 -0.5)
			(end 0 0.5)
			(stroke
				(width 0.1)
				(type solid)
			)
			(layer "F.Fab")
		)
		(fp_line
			(start -1.35 -0.75)
			(end -1.35 0.75)
			(stroke
				(width 0.2)
				(type solid)
			)
			(layer "F.Fab")
		)
		(fp_text user "${REFERENCE}"
			(at -0.00001 0.09601 180)
			(unlocked yes)
			(layer "F.Fab")
			(effects
				(font
					(face "Arial")
					(size 0.63 0.63)
					(thickness 0.1)
				)
				(justify left bottom)
			)
		)
		(pad "1" smd rect
			(at -0.75 0 180)
			(size 0.8 0.9)
			(layers "F.Cu" "F.Mask" "F.Paste")
			(net "NetC74_1")
			(solder_mask_margin 0)
			(solder_paste_margin 0)
		)
		(pad "2" smd rect
			(at 0.75 0 180)
			(size 0.8 0.9)
			(layers "F.Cu" "F.Mask" "F.Paste")
			(net "P3V3_FB")
			(solder_mask_margin 0)
			(solder_paste_margin 0)
		)
	)
	(footprint "Vault:RESC1005X40X25ML05T10"
		(layer "F.Cu")
		(at 217.2261 114.1162 180)
		(property "Reference" "R6"
			(at 0.6 -1.593345 0)
			(unlocked yes)
			(layer "F.SilkS")
			(effects
				(font
					(size 0.762 0.762)
					(thickness 0.2286)
				)
				(justify left bottom)
			)
		)
		(property "Value" "2.21_1%_0402"
			(at 10.44471 4.536755 0)
			(unlocked yes)
			(layer "F.SilkS")
			(hide yes)
			(effects
				(font
					(size 0.762 0.762)
					(thickness 0.2286)
				)
				(justify left bottom)
			)
		)
		(sheetname "POWER")
		(sheetfile "POWER.kicad_sch")
		(duplicate_pad_numbers_are_jumpers no)
		(pad "1" smd rect
			(at -0.475 0 270)
			(size 0.65 0.7)
			(layers "F.Cu" "F.Mask" "F.Paste")
			(net "NetC3_2")
		)
		(pad "2" smd rect
			(at 0.475 0 270)
			(size 0.65 0.7)
			(layers "F.Cu" "F.Mask" "F.Paste")
			(net "NetL1_1")
		)
	)
	(footprint "Vault:RESC1005X40X25LL05T10"
		(layer "F.Cu")
		(at 166.8011 83.2162)
		(property "Reference" "R88"
			(at -1.7464 0.026921 0)
			(unlocked yes)
			(layer "F.SilkS")
			(effects
				(font
					(size 0.762 0.762)
					(thickness 0.2286)
				)
			)
		)
		(property "Value" "10K_1%_0402"
			(at -2.579871 8.061915 270)
			(unlocked yes)
			(layer "F.SilkS")
			(hide yes)
			(effects
				(font
					(size 0.762 0.762)
					(thickness 0.2286)
				)
			)
		)
		(sheetname "USBUart_DipSelects")
		(sheetfile "USBUart_DipSelects.kicad_sch")
		(duplicate_pad_numbers_are_jumpers no)
		(pad "1" smd rect
			(at -0.375 0 90)
			(size 0.45 0.5)
			(layers "F.Cu" "F.Mask" "F.Paste")
			(net "+3.3V")
		)
		(pad "2" smd rect
			(at 0.375 0 90)
			(size 0.45 0.5)
			(layers "F.Cu" "F.Mask" "F.Paste")
			(net "DIP_SW_UART_SEL")
		)
	)
)
